# S9S_MB_2U (Grand Teton) — schematic netlist excerpt (pin names and nets, part order shuffled) for the footprints in the layout excerpt that follows; sources: Cadence DE-HDL packaged netlist, KiCad conversion of 03242023_DA0F0TMBIJ0_F0T_Motherboard_J_brd_V01_OCP.brd

R1748  Q_RES  0 5% CHIP  pkg 0402LF  page 202 : A = FM_ESPI_PLD_EN ; B = FM_ESPI_PLD_R_EN_BUF
R3631  Q_RES  0 5% EMPTY  pkg 0402LF  page 163 : A = HP_LVC3_OCP_V3_2_EN ; B = P3V3_OCP_EN_2

(kicad_pcb
	(version 20260206)
	(generator "pcbnew")
	(generator_version "10.0")
	(general
		(thickness 1.6)
		(legacy_teardrops no)
	)
	(paper "A4")
	(title_block
		(title "03242023_DA0F0TMBIJ0_F0T_Motherboard_J_brd_V01_OCP.brd")
		(comment 1 "Grand Teton / footprints 57-58 of 6105")
	)
	(layers
		(0 "F.Cu" signal "TOP")
		(4 "In1.Cu" signal "GND")
		(6 "In2.Cu" signal "IN1")
		(8 "In3.Cu" signal "GND1")
		(10 "In4.Cu" signal "IN2")
		(12 "In5.Cu" signal "GND2")
		(14 "In6.Cu" signal "IN3")
		(16 "In7.Cu" signal "GND3")
		(18 "In8.Cu" signal "VCC")
		(20 "In9.Cu" signal "VCC1")
		(22 "In10.Cu" signal "GND4")
		(24 "In11.Cu" signal "IN4")
		(26 "In12.Cu" signal "GND5")
		(28 "In13.Cu" signal "IN5")
		(30 "In14.Cu" signal "GND6")
		(32 "In15.Cu" signal "IN6")
		(34 "In16.Cu" signal "GND7")
		(2 "B.Cu" signal "BOTTOM")
		(9 "F.Adhes" user "F.Adhesive")
		(11 "B.Adhes" user "B.Adhesive")
		(13 "F.Paste" user "Package Geometry/Pastemask Top")
		(15 "B.Paste" user "Package Geometry/Pastemask Bottom")
		(5 "F.SilkS" user "Ref Des/Silkscreen Top")
		(7 "B.SilkS" user "Ref Des/Silkscreen Bottom")
		(1 "F.Mask" user "Board Geometry/Soldermask Top")
		(3 "B.Mask" user "Board Geometry/Soldermask Bottom")
		(17 "Dwgs.User" user "User.Drawings")
		(19 "Cmts.User" user "User.Comments")
		(21 "Eco1.User" user "User.Eco1")
		(23 "Eco2.User" user "User.Eco2")
		(25 "Edge.Cuts" user "Board Geometry/Outline")
		(27 "Margin" user)
		(31 "F.CrtYd" user "Package Geometry/Place Bound Top")
		(29 "B.CrtYd" user "Package Geometry/Place Bound Bottom")
		(35 "F.Fab" user "Ref Des/Assembly Top")
		(33 "B.Fab" user "Ref Des/Assembly Bottom")
	)
	(footprint ""
		(layer "F.Cu")
		(at 335.209134 -18.79727 -90)
		(property "Reference" "R1748"
			(at 0 0 270)
			(layer "F.SilkS")
			(hide yes)
			(effects
				(font
					(size 1.27 1.27)
				)
			)
		)
		(property "Value" ""
			(at 0 0 270)
			(layer "F.Fab")
			(effects
				(font
					(size 1.27 1.27)
				)
			)
		)
		(duplicate_pad_numbers_are_jumpers no)
		(fp_line
			(start -0.7874 0.4064)
			(end -0.7874 -0.4064)
			(stroke
				(width 0.1524)
				(type default)
			)
			(layer "F.SilkS")
		)
		(fp_line
			(start 0.7874 0.4064)
			(end -0.7874 0.4064)
			(stroke
				(width 0.1524)
				(type default)
			)
			(layer "F.SilkS")
		)
		(fp_line
			(start -0.7874 -0.4064)
			(end 0.7874 -0.4064)
			(stroke
				(width 0.1524)
				(type default)
			)
			(layer "F.SilkS")
		)
		(fp_line
			(start 0.7874 -0.4064)
			(end 0.7874 0.4064)
			(stroke
				(width 0.1524)
				(type default)
			)
			(layer "F.SilkS")
		)
		(fp_line
			(start -0.67945 0.3048)
			(end -0.67945 -0.305054)
			(stroke
				(width 0.1)
				(type default)
			)
			(layer "F.Fab")
		)
		(fp_line
			(start -0.12065 0.3048)
			(end -0.67945 0.3048)
			(stroke
				(width 0.1)
				(type default)
			)
			(layer "F.Fab")
		)
		(fp_line
			(start 0.120396 0.3048)
			(end 0.120396 0.2794)
			(stroke
				(width 0.1)
				(type default)
			)
			(layer "F.Fab")
		)
		(fp_line
			(start 0.67945 0.3048)
			(end 0.120396 0.3048)
			(stroke
				(width 0.1)
				(type default)
			)
			(layer "F.Fab")
		)
		(fp_line
			(start -0.12065 0.2794)
			(end -0.12065 0.3048)
			(stroke
				(width 0.1)
				(type default)
			)
			(layer "F.Fab")
		)
		(fp_line
			(start 0.120396 0.2794)
			(end -0.12065 0.2794)
			(stroke
				(width 0.1)
				(type default)
			)
			(layer "F.Fab")
		)
		(fp_line
			(start -0.12065 -0.2794)
			(end 0.12065 -0.2794)
			(stroke
				(width 0.1)
				(type default)
			)
			(layer "F.Fab")
		)
		(fp_line
			(start 0.12065 -0.2794)
			(end 0.12065 -0.3048)
			(stroke
				(width 0.1)
				(type default)
			)
			(layer "F.Fab")
		)
		(fp_line
			(start 0.12065 -0.3048)
			(end 0.67945 -0.3048)
			(stroke
				(width 0.1)
				(type default)
			)
			(layer "F.Fab")
		)
		(fp_line
			(start 0.67945 -0.3048)
			(end 0.67945 0.3048)
			(stroke
				(width 0.1)
				(type default)
			)
			(layer "F.Fab")
		)
		(fp_line
			(start -0.67945 -0.305054)
			(end -0.12065 -0.305054)
			(stroke
				(width 0.1)
				(type default)
			)
			(layer "F.Fab")
		)
		(fp_line
			(start -0.12065 -0.305054)
			(end -0.12065 -0.2794)
			(stroke
				(width 0.1)
				(type default)
			)
			(layer "F.Fab")
		)
		(pad "1" smd circle
			(at -0.40005 0 270)
			(size 0 0)
			(layers "F.Cu" "F.Mask" "F.Paste")
			(net "FM_ESPI_PLD_EN")
		)
		(pad "2" smd circle
			(at 0.40005 0 270)
			(size 0 0)
			(layers "F.Cu" "F.Mask" "F.Paste")
			(net "FM_ESPI_PLD_R_EN_BUF")
		)
	)
	(footprint ""
		(layer "F.Cu")
		(at 68.64096 -61.158628 -90)
		(property "Reference" "R3631"
			(at 0 0 270)
			(layer "F.SilkS")
			(hide yes)
			(effects
				(font
					(size 1.27 1.27)
				)
			)
		)
		(property "Value" ""
			(at 0 0 270)
			(layer "F.Fab")
			(effects
				(font
					(size 1.27 1.27)
				)
			)
		)
		(duplicate_pad_numbers_are_jumpers no)
		(fp_line
			(start -0.7874 0.4064)
			(end -0.7874 -0.4064)
			(stroke
				(width 0.1524)
				(type default)
			)
			(layer "F.SilkS")
		)
		(fp_line
			(start 0.7874 0.4064)
			(end -0.7874 0.4064)
			(stroke
				(width 0.1524)
				(type default)
			)
			(layer "F.SilkS")
		)
		(fp_line
			(start -0.7874 -0.4064)
			(end 0.7874 -0.4064)
			(stroke
				(width 0.1524)
				(type default)
			)
			(layer "F.SilkS")
		)
		(fp_line
			(start 0.7874 -0.4064)
			(end 0.7874 0.4064)
			(stroke
				(width 0.1524)
				(type default)
			)
			(layer "F.SilkS")
		)
		(fp_line
			(start -0.67945 0.3048)
			(end -0.67945 -0.305054)
			(stroke
				(width 0.1)
				(type default)
			)
			(layer "F.Fab")
		)
		(fp_line
			(start -0.12065 0.3048)
			(end -0.67945 0.3048)
			(stroke
				(width 0.1)
				(type default)
			)
			(layer "F.Fab")
		)
		(fp_line
			(start 0.120396 0.3048)
			(end 0.120396 0.2794)
			(stroke
				(width 0.1)
				(type default)
			)
			(layer "F.Fab")
		)
		(fp_line
			(start 0.67945 0.3048)
			(end 0.120396 0.3048)
			(stroke
				(width 0.1)
				(type default)
			)
			(layer "F.Fab")
		)
		(fp_line
			(start -0.12065 0.2794)
			(end -0.12065 0.3048)
			(stroke
				(width 0.1)
				(type default)
			)
			(layer "F.Fab")
		)
		(fp_line
			(start 0.120396 0.2794)
			(end -0.12065 0.2794)
			(stroke
				(width 0.1)
				(type default)
			)
			(layer "F.Fab")
		)
		(fp_line
			(start -0.12065 -0.2794)
			(end 0.12065 -0.2794)
			(stroke
				(width 0.1)
				(type default)
			)
			(layer "F.Fab")
		)
		(fp_line
			(start 0.12065 -0.2794)
			(end 0.12065 -0.3048)
			(stroke
				(width 0.1)
				(type default)
			)
			(layer "F.Fab")
		)
		(fp_line
			(start 0.12065 -0.3048)
			(end 0.67945 -0.3048)
			(stroke
				(width 0.1)
				(type default)
			)
			(layer "F.Fab")
		)
		(fp_line
			(start 0.67945 -0.3048)
			(end 0.67945 0.3048)
			(stroke
				(width 0.1)
				(type default)
			)
			(layer "F.Fab")
		)
		(fp_line
			(start -0.67945 -0.305054)
			(end -0.12065 -0.305054)
			(stroke
				(width 0.1)
				(type default)
			)
			(layer "F.Fab")
		)
		(fp_line
			(start -0.12065 -0.305054)
			(end -0.12065 -0.2794)
			(stroke
				(width 0.1)
				(type default)
			)
			(layer "F.Fab")
		)
		(pad "1" smd circle
			(at -0.40005 0 270)
			(size 0 0)
			(layers "F.Cu" "F.Mask" "F.Paste")
			(net "HP_LVC3_OCP_V3_2_EN")
		)
		(pad "2" smd circle
			(at 0.40005 0 270)
			(size 0 0)
			(layers "F.Cu" "F.Mask" "F.Paste")
			(net "P3V3_OCP_EN_2")
		)
	)
)
